(kicad_pcb
	(version 20241229)
	(generator "pcbnew")
	(generator_version "9.0")
	(general
		(thickness 1.62)
		(legacy_teardrops no)
	)
	(paper "A4")
	(title_block
		(title "OCuLink to 10GbE adapter")
		(date "2026-02-23")
		(rev "1.1.0")
		(company "Antmicro Ltd")
		(comment 1 "www.antmicro.com")
		(comment 9 "footprints 102-106 of 510")
	)
	(layers
		(0 "F.Cu" signal)
		(4 "In1.Cu" signal)
		(6 "In2.Cu" signal)
		(8 "In3.Cu" signal)
		(10 "In4.Cu" signal)
		(12 "In5.Cu" signal)
		(14 "In6.Cu" signal)
		(2 "B.Cu" signal)
		(9 "F.Adhes" user "F.Adhesive")
		(11 "B.Adhes" user "B.Adhesive")
		(13 "F.Paste" user)
		(15 "B.Paste" user)
		(5 "F.SilkS" user "F.Silkscreen")
		(7 "B.SilkS" user "B.Silkscreen")
		(1 "F.Mask" user)
		(3 "B.Mask" user)
		(17 "Dwgs.User" user "User.Drawings")
		(19 "Cmts.User" user "User.Comments")
		(21 "Eco1.User" user "User.Eco1")
		(23 "Eco2.User" user "User.Eco2")
		(25 "Edge.Cuts" user)
		(27 "Margin" user)
		(31 "F.CrtYd" user "F.Courtyard")
		(29 "B.CrtYd" user "B.Courtyard")
		(35 "F.Fab" user)
		(33 "B.Fab" user)
	)
	(footprint "antmicro-footprints:C_0603_1608Metric"
		(layer "F.Cu")
		(at 72.45 103.7 90)
		(descr "Capacitor SMD 0603")
		(tags "capacitor 0603")
		(property "Reference" "C186"
			(at -1.36 1.54 90)
			(layer "F.SilkS")
			(effects
				(font
					(size 0.7 0.7)
					(thickness 0.15)
				)
				(justify left bottom)
			)
		)
		(property "Value" "C_10u_10V_X7R_0603"
			(at -1.42757 1.770288 90)
			(layer "F.Fab")
			(hide yes)
			(effects
				(font
					(size 0.7 0.7)
					(thickness 0.15)
				)
				(justify left bottom)
			)
		)
		(property "Datasheet" "https://www.murata.com/products/productdetail?partno=GRM188Z71A106KA73%23"
			(at 0 0 90)
			(layer "F.Fab")
			(hide yes)
			(effects
				(font
					(size 1.27 1.27)
					(thickness 0.15)
				)
			)
		)
		(property "Description" "SMD Multilayer Ceramic Capacitor,  10µF, 10V, 0603, ±10%, X7R"
			(at 0 0 90)
			(layer "F.Fab")
			(hide yes)
			(effects
				(font
					(size 1.27 1.27)
					(thickness 0.15)
				)
			)
		)
		(property "MPN" "GRM188Z71A106KA73D"
			(at 0 0 90)
			(unlocked yes)
			(layer "F.Fab")
			(hide yes)
			(effects
				(font
					(size 1 1)
					(thickness 0.15)
				)
			)
		)
		(property "Val" "10u"
			(at 0 0 90)
			(unlocked yes)
			(layer "F.Fab")
			(hide yes)
			(effects
				(font
					(size 1 1)
					(thickness 0.15)
				)
			)
		)
		(property "Voltage" "10V"
			(at 0 0 90)
			(unlocked yes)
			(layer "F.Fab")
			(hide yes)
			(effects
				(font
					(size 1 1)
					(thickness 0.15)
				)
			)
		)
		(property "Dielectric" "X7R"
			(at 0 0 90)
			(unlocked yes)
			(layer "F.Fab")
			(hide yes)
			(effects
				(font
					(size 1 1)
					(thickness 0.15)
				)
			)
		)
		(property "Manufacturer" "Murata"
			(at 0 0 90)
			(unlocked yes)
			(layer "F.Fab")
			(hide yes)
			(effects
				(font
					(size 1 1)
					(thickness 0.15)
				)
			)
		)
		(property "License" "Apache-2.0"
			(at 0 0 90)
			(unlocked yes)
			(layer "F.Fab")
			(hide yes)
			(effects
				(font
					(size 1 1)
					(thickness 0.15)
				)
			)
		)
		(property "Author" "Antmicro"
			(at 0 0 90)
			(unlocked yes)
			(layer "F.Fab")
			(hide yes)
			(effects
				(font
					(size 1 1)
					(thickness 0.15)
				)
			)
		)
		(sheetname "/X710-AT2 power/")
		(sheetfile "x710-at2-power.kicad_sch")
		(attr smd)
		(fp_line
			(start -0.15 -0.4)
			(end 0.15 -0.4)
			(stroke
				(width 0.15)
				(type solid)
			)
			(layer "F.SilkS")
		)
		(fp_line
			(start -0.15 0.4)
			(end 0.15 0.4)
			(stroke
				(width 0.15)
				(type solid)
			)
			(layer "F.SilkS")
		)
		(fp_rect
			(start -1.25 -0.65)
			(end 1.25 0.65)
			(stroke
				(width 0.05)
				(type solid)
			)
			(fill no)
			(layer "F.CrtYd")
		)
		(fp_rect
			(start -0.8 -0.4)
			(end 0.8 0.4)
			(stroke
				(width 0.15)
				(type solid)
			)
			(fill no)
			(layer "F.Fab")
		)
		(pad "1" smd roundrect
			(at -0.7 0 90)
			(size 0.8 1)
			(layers "F.Cu" "F.Mask" "F.Paste")
			(roundrect_rratio 0.2)
			(net 28 "GND")
			(pintype "passive")
		)
		(pad "2" smd roundrect
			(at 0.7 0 90)
			(size 0.8 1)
			(layers "F.Cu" "F.Mask" "F.Paste")
			(roundrect_rratio 0.2)
			(net 24 "XFI_PVDD")
			(pintype "passive")
		)
	)
	(footprint "antmicro-footprints:C_0805_2012Metric"
		(layer "F.Cu")
		(at 69.45 110.39 90)
		(descr "Capacitor SMD 0805")
		(tags "capacitor SMD 0805")
		(property "Reference" "C163"
			(at -3.63 5.24 90)
			(layer "F.SilkS")
			(effects
				(font
					(size 0.7 0.7)
					(thickness 0.15)
				)
				(justify left bottom)
			)
		)
		(property "Value" "C_100u_0805"
			(at -2.055717 1.963153 90)
			(layer "F.Fab")
			(hide yes)
			(effects
				(font
					(size 0.7 0.7)
					(thickness 0.15)
				)
				(justify left bottom)
			)
		)
		(property "Datasheet" "https://www.murata.com/products/productdetail?partno=GRM21BR60J107ME15%23"
			(at 0 0 90)
			(layer "F.Fab")
			(hide yes)
			(effects
				(font
					(size 1.27 1.27)
					(thickness 0.15)
				)
			)
		)
		(property "Description" "SMD Multilayer Ceramic Capacitor, 100 µF, 6.3 V, 0805 [2012 Metric], ± 20%, X5R, GRM Series"
			(at 0 0 90)
			(layer "F.Fab")
			(hide yes)
			(effects
				(font
					(size 1.27 1.27)
					(thickness 0.15)
				)
			)
		)
		(property "MPN" "GRM21BR60J107ME15L"
			(at 0 0 90)
			(unlocked yes)
			(layer "F.Fab")
			(hide yes)
			(effects
				(font
					(size 1 1)
					(thickness 0.15)
				)
			)
		)
		(property "Manufacturer" "Murata"
			(at 0 0 90)
			(unlocked yes)
			(layer "F.Fab")
			(hide yes)
			(effects
				(font
					(size 1 1)
					(thickness 0.15)
				)
			)
		)
		(property "License" "Apache-2.0"
			(at 0 0 90)
			(unlocked yes)
			(layer "F.Fab")
			(hide yes)
			(effects
				(font
					(size 1 1)
					(thickness 0.15)
				)
			)
		)
		(property "Author" "Antmicro"
			(at 0 0 90)
			(unlocked yes)
			(layer "F.Fab")
			(hide yes)
			(effects
				(font
					(size 1 1)
					(thickness 0.15)
				)
			)
		)
		(property "Val" "100u"
			(at 0 0 90)
			(unlocked yes)
			(layer "F.Fab")
			(hide yes)
			(effects
				(font
					(size 1 1)
					(thickness 0.15)
				)
			)
		)
		(property "Voltage" ""
			(at 0 0 90)
			(unlocked yes)
			(layer "F.Fab")
			(hide yes)
			(effects
				(font
					(size 1 1)
					(thickness 0.15)
				)
			)
		)
		(property "Dielectric" ""
			(at 0 0 90)
			(unlocked yes)
			(layer "F.Fab")
			(hide yes)
			(effects
				(font
					(size 1 1)
					(thickness 0.15)
				)
			)
		)
		(property "Public" "False"
			(at 0 0 90)
			(unlocked yes)
			(layer "F.Fab")
			(hide yes)
			(effects
				(font
					(size 1 1)
					(thickness 0.15)
				)
			)
		)
		(sheetname "/X710-AT2 power/")
		(sheetfile "x710-at2-power.kicad_sch")
		(attr smd)
		(fp_line
			(start -0.3 -0.7)
			(end 0.3 -0.7)
			(stroke
				(width 0.15)
				(type solid)
			)
			(layer "F.SilkS")
		)
		(fp_line
			(start -0.3 0.7)
			(end 0.3 0.7)
			(stroke
				(width 0.15)
				(type solid)
			)
			(layer "F.SilkS")
		)
		(fp_rect
			(start 1.95 -0.9)
			(end -1.95 0.9)
			(stroke
				(width 0.05)
				(type default)
			)
			(fill no)
			(layer "F.CrtYd")
		)
		(fp_rect
			(start -0.95 -0.675)
			(end 0.95 0.675)
			(stroke
				(width 0.15)
				(type solid)
			)
			(fill no)
			(layer "F.Fab")
		)
		(pad "1" smd roundrect
			(at -1.1 0 90)
			(size 1.2 1.3)
			(layers "F.Cu" "F.Mask" "F.Paste")
			(roundrect_rratio 0.25)
			(net 28 "GND")
			(pintype "passive")
		)
		(pad "2" smd roundrect
			(at 1.1 0 90)
			(size 1.2 1.3)
			(layers "F.Cu" "F.Mask" "F.Paste")
			(roundrect_rratio 0.25)
			(net 5 "P0_AVDDL")
			(pintype "passive")
		)
	)
	(footprint "antmicro-footprints:C_0402_1005Metric"
		(layer "F.Cu")
		(at 54.4 96.199999 -90)
		(descr "Capacitor SMD 0402")
		(tags "capacitor SMD 0402")
		(property "Reference" "C42"
			(at 0.840001 0.41 90)
			(layer "F.SilkS")
			(effects
				(font
					(size 0.7 0.7)
					(thickness 0.15)
				)
				(justify right top)
			)
		)
		(property "Value" "C_100n_0402"
			(at -1.022927 2.155213 90)
			(layer "F.Fab")
			(hide yes)
			(effects
				(font
					(size 0.7 0.7)
					(thickness 0.15)
				)
				(justify right top)
			)
		)
		(property "Datasheet" "https://www.murata.com/products/productdetail?partno=GRM155R61H104KE14%23"
			(at 0 0 90)
			(layer "F.Fab")
			(hide yes)
			(effects
				(font
					(size 1.27 1.27)
					(thickness 0.15)
				)
			)
		)
		(property "Description" "SMD Multilayer Ceramic Capacitor, 0.1 µF, 50 V, 0402 [1005 Metric], ± 10%, X5R, GRM Series"
			(at 0 0 90)
			(layer "F.Fab")
			(hide yes)
			(effects
				(font
					(size 1.27 1.27)
					(thickness 0.15)
				)
			)
		)
		(property "MPN" "GRM155R61H104KE14D"
			(at 0 0 270)
			(unlocked yes)
			(layer "F.Fab")
			(hide yes)
			(effects
				(font
					(size 1 1)
					(thickness 0.15)
				)
			)
		)
		(property "Manufacturer" "Murata"
			(at 0 0 270)
			(unlocked yes)
			(layer "F.Fab")
			(hide yes)
			(effects
				(font
					(size 1 1)
					(thickness 0.15)
				)
			)
		)
		(property "License" "Apache-2.0"
			(at 0 0 270)
			(unlocked yes)
			(layer "F.Fab")
			(hide yes)
			(effects
				(font
					(size 1 1)
					(thickness 0.15)
				)
			)
		)
		(property "Author" "Antmicro"
			(at 0 0 270)
			(unlocked yes)
			(layer "F.Fab")
			(hide yes)
			(effects
				(font
					(size 1 1)
					(thickness 0.15)
				)
			)
		)
		(property "Val" "100n"
			(at 0 0 270)
			(unlocked yes)
			(layer "F.Fab")
			(hide yes)
			(effects
				(font
					(size 1 1)
					(thickness 0.15)
				)
			)
		)
		(property "Voltage" "50V"
			(at 0 0 270)
			(unlocked yes)
			(layer "F.Fab")
			(hide yes)
			(effects
				(font
					(size 1 1)
					(thickness 0.15)
				)
			)
		)
		(property "Dielectric" "X5R"
			(at 0 0 270)
			(unlocked yes)
			(layer "F.Fab")
			(hide yes)
			(effects
				(font
					(size 1 1)
					(thickness 0.15)
				)
			)
		)
		(sheetname "/Power/")
		(sheetfile "power.kicad_sch")
		(attr smd)
		(fp_rect
			(start -0.925 -0.47)
			(end 0.925 0.47)
			(stroke
				(width 0.05)
				(type default)
			)
			(fill no)
			(layer "F.CrtYd")
		)
		(fp_line
			(start -0.494 0.248)
			(end -0.494 -0.25)
			(stroke
				(width 0.15)
				(type solid)
			)
			(layer "F.Fab")
		)
		(fp_line
			(start 0.504 0.248)
			(end -0.494 0.248)
			(stroke
				(width 0.15)
				(type solid)
			)
			(layer "F.Fab")
		)
		(fp_line
			(start -0.494 -0.25)
			(end 0.504 -0.25)
			(stroke
				(width 0.15)
				(type solid)
			)
			(layer "F.Fab")
		)
		(fp_line
			(start 0.504 -0.25)
			(end 0.504 0.248)
			(stroke
				(width 0.15)
				(type solid)
			)
			(layer "F.Fab")
		)
		(pad "1" smd roundrect
			(at -0.48 0 270)
			(size 0.59 0.64)
			(layers "F.Cu" "F.Mask" "F.Paste")
			(roundrect_rratio 0.25)
			(net 28 "GND")
			(pintype "passive")
		)
		(pad "2" smd roundrect
			(at 0.48 0 270)
			(size 0.59 0.64)
			(layers "F.Cu" "F.Mask" "F.Paste")
			(roundrect_rratio 0.25)
			(net 314 "VCC")
			(pintype "passive")
		)
	)
	(footprint "antmicro-footprints:R_0402_1005Metric"
		(layer "F.Cu")
		(at 111.35 95.35 -90)
		(descr "Resistor SMD 0402")
		(tags "resistor SMD 0402")
		(property "Reference" "R65"
			(at -2.9 -0.334999 90)
			(layer "F.SilkS")
			(effects
				(font
					(size 0.7 0.7)
					(thickness 0.15)
				)
				(justify left bottom)
			)
		)
		(property "Value" "R_3k3_0402"
			(at -1.011843 1.772046 90)
			(layer "F.Fab")
			(hide yes)
			(effects
				(font
					(size 0.7 0.7)
					(thickness 0.15)
				)
				(justify right top)
			)
		)
		(property "Datasheet" "https://www.bourns.com/docs/product-datasheets/cr.pdf"
			(at 0 0 90)
			(layer "F.Fab")
			(hide yes)
			(effects
				(font
					(size 1.27 1.27)
					(thickness 0.15)
				)
			)
		)
		(property "Description" "SMD Chip Resistor, 3.3 kohm, ± 1%, 63 mW, 0402 [1005 Metric], Thick Film, General Purpose"
			(at 0 0 90)
			(layer "F.Fab")
			(hide yes)
			(effects
				(font
					(size 1.27 1.27)
					(thickness 0.15)
				)
			)
		)
		(property "MPN" "CR0402-FX-3301GLF"
			(at 0 0 270)
			(unlocked yes)
			(layer "F.Fab")
			(hide yes)
			(effects
				(font
					(size 1 1)
					(thickness 0.15)
				)
			)
		)
		(property "Manufacturer" "Bourns"
			(at 0 0 270)
			(unlocked yes)
			(layer "F.Fab")
			(hide yes)
			(effects
				(font
					(size 1 1)
					(thickness 0.15)
				)
			)
		)
		(property "License" "Apache-2.0"
			(at 0 0 270)
			(unlocked yes)
			(layer "F.Fab")
			(hide yes)
			(effects
				(font
					(size 1 1)
					(thickness 0.15)
				)
			)
		)
		(property "Author" "Antmicro"
			(at 0 0 270)
			(unlocked yes)
			(layer "F.Fab")
			(hide yes)
			(effects
				(font
					(size 1 1)
					(thickness 0.15)
				)
			)
		)
		(property "Val" "3k3"
			(at 0 0 270)
			(unlocked yes)
			(layer "F.Fab")
			(hide yes)
			(effects
				(font
					(size 1 1)
					(thickness 0.15)
				)
			)
		)
		(property "Tolerance" "1%"
			(at 0 0 270)
			(unlocked yes)
			(layer "F.Fab")
			(hide yes)
			(effects
				(font
					(size 1 1)
					(thickness 0.15)
				)
			)
		)
		(sheetname "/X710-AT2 10GbE/")
		(sheetfile "x710-at2-10gbe.kicad_sch")
		(attr smd)
		(fp_rect
			(start -0.925 -0.47)
			(end 0.925 0.47)
			(stroke
				(width 0.05)
				(type default)
			)
			(fill no)
			(layer "F.CrtYd")
		)
		(fp_rect
			(start -0.5 -0.25)
			(end 0.5 0.25)
			(stroke
				(width 0.15)
				(type solid)
			)
			(fill no)
			(layer "F.Fab")
		)
		(pad "1" smd roundrect
			(at -0.48 0 270)
			(size 0.59 0.64)
			(layers "F.Cu" "F.Mask" "F.Paste")
			(roundrect_rratio 0.25)
			(net 130 "/X710-AT2 10GbE/MDC0_SCL0")
			(pintype "passive")
		)
		(pad "2" smd roundrect
			(at 0.48 0 270)
			(size 0.59 0.64)
			(layers "F.Cu" "F.Mask" "F.Paste")
			(roundrect_rratio 0.25)
			(net 7 "+3V3")
			(pintype "passive")
		)
	)
	(footprint "antmicro-footprints:TDFN-8-1EP_2x3x0.75mm_P0.5mm_EP1.75x1.63mm"
		(layer "F.Cu")
		(at 111.15 103.4 -90)
		(descr "8-Lead Plastic Dual Flat, 2x3mm Body")
		(tags "DFN 0.5")
		(property "Reference" "U14"
			(at -0.31 1.85 90)
			(layer "F.SilkS")
			(effects
				(font
					(size 0.7 0.7)
					(thickness 0.15)
				)
				(justify right top)
			)
		)
		(property "Value" "MAX31740ATA+T"
			(at -2.1 3 90)
			(layer "F.Fab")
			(hide yes)
			(effects
				(font
					(size 0.7 0.7)
					(thickness 0.15)
				)
				(justify right top)
			)
		)
		(property "Datasheet" "https://www.analog.com/media/en/technical-documentation/data-sheets/max31740.pdf"
			(at 0 0 90)
			(layer "F.Fab")
			(hide yes)
			(effects
				(font
					(size 1.27 1.27)
					(thickness 0.15)
				)
			)
		)
		(property "Description" "Pwm fan speed controller, temperature measurement, Control speed of 2-, 3-, 4- Wire Fans"
			(at 0 0 90)
			(layer "F.Fab")
			(hide yes)
			(effects
				(font
					(size 1.27 1.27)
					(thickness 0.15)
				)
			)
		)
		(property "MPN" "MAX31740ATA+T"
			(at 0 0 270)
			(unlocked yes)
			(layer "F.Fab")
			(hide yes)
			(effects
				(font
					(size 1 1)
					(thickness 0.15)
				)
			)
		)
		(property "Manufacturer" "Analog Devices"
			(at 0 0 270)
			(unlocked yes)
			(layer "F.Fab")
			(hide yes)
			(effects
				(font
					(size 1 1)
					(thickness 0.15)
				)
			)
		)
		(property "Author" "Antmicro"
			(at 0 0 270)
			(unlocked yes)
			(layer "F.Fab")
			(hide yes)
			(effects
				(font
					(size 1 1)
					(thickness 0.15)
				)
			)
		)
		(property "License" "Apache-2.0"
			(at 0 0 270)
			(unlocked yes)
			(layer "F.Fab")
			(hide yes)
			(effects
				(font
					(size 1 1)
					(thickness 0.15)
				)
			)
		)
		(sheetname "/Fan controller/")
		(sheetfile "fan-controller.kicad_sch")
		(attr smd exclude_from_pos_files exclude_from_bom dnp)
		(fp_circle
			(center -1.8 -1.1)
			(end -1.75 -1.1)
			(stroke
				(width 0.15)
				(type solid)
			)
			(fill yes)
			(layer "F.SilkS")
		)
		(fp_rect
			(start -2.05 -1.25)
			(end 2.05 1.25)
			(stroke
				(width 0.05)
				(type default)
			)
			(fill no)
			(layer "F.CrtYd")
		)
		(pad "1" smd rect
			(at -1.5 -0.75)
			(size 0.3 0.75)
			(layers "F.Cu" "F.Mask" "F.Paste")
			(net 399 "/Fan controller/DMIN")
			(pinfunction "DMIN")
			(pintype "passive")
		)
		(pad "2" smd rect
			(at -1.5 -0.25)
			(size 0.3 0.75)
			(layers "F.Cu" "F.Mask" "F.Paste")
			(net 400 "/Fan controller/SLOPE")
			(pinfunction "SLOPE")
			(pintype "passive")
		)
		(pad "3" smd rect
			(at -1.5 0.25)
			(size 0.3 0.75)
			(layers "F.Cu" "F.Mask" "F.Paste")
			(net 385 "/Fan controller/SENSE")
			(pinfunction "SENSE")
			(pintype "passive")
		)
		(pad "4" smd rect
			(at -1.5 0.75)
			(size 0.3 0.75)
			(layers "F.Cu" "F.Mask" "F.Paste")
			(net 28 "GND")
			(pinfunction "GND")
			(pintype "power_in")
		)
		(pad "5" smd rect
			(at 1.5 0.75)
			(size 0.3 0.75)
			(layers "F.Cu" "F.Mask" "F.Paste")
			(net 387 "/Fan controller/FREQ")
			(pinfunction "FREQ")
			(pintype "passive")
		)
		(pad "6" smd rect
			(at 1.5 0.25)
			(size 0.3 0.75)
			(layers "F.Cu" "F.Mask" "F.Paste")
			(net 398 "/Fan controller/D0")
			(pinfunction "D0")
			(pintype "passive")
		)
		(pad "7" smd rect
			(at 1.5 -0.25)
			(size 0.3 0.75)
			(layers "F.Cu" "F.Mask" "F.Paste")
			(net 390 "/Fan controller/PWM")
			(pinfunction "PWM_OUT")
			(pintype "output")
		)
		(pad "8" smd rect
			(at 1.5 -0.75)
			(size 0.3 0.75)
			(layers "F.Cu" "F.Mask" "F.Paste")
			(net 388 "/Fan controller/+5V")
			(pinfunction "VDD")
			(pintype "power_in")
		)
		(pad "9" smd rect
			(at 0 0)
			(size 1.63 1.75)
			(layers "F.Cu" "F.Mask" "F.Paste")
			(net 28 "GND")
			(pinfunction "EP")
			(pintype "power_in")
		)
	)
)
